# Barreleye-G2_Tri-mode BPX24-DVT-X01-SKU-BOM-X07-20171222_Final.xls.xlsx — POP_GA (bom)
| FOXCONN TECHNOLOGY GROUP |  |  |  |  |  |  |  |  |  |  |  |  |
| BILL OF MATERIAL |  |  |  |  |  |  |  |  |  |  |  |  |
| REV OF  BOM |  | CUSTOMER | <name> |  | CUSTOMER P/N |  | PRODUCT CODE |  | PWA  REV |  | DATE |  |
| Sourcing (Single/Sole/Multi) | Critical Commodity (Y or N) | Component Class (1, 2, other) | Customer PSL (Y or N) | Item Number | Foxconn P/N | Customer P/N | Part Description | Manufacturer  Full Name | Manufacturer  Part Number | Qty | RoHS Status | Location |
